(kicad_pcb
	(version 20260206)
	(generator "pcbnew")
	(generator_version "10.0")
	(general
		(thickness 1.6)
		(legacy_teardrops no)
	)
	(paper "A4")
	(title_block
		(title "v1-chassis-manager — T6M_CM_d_v01_1031_1645.brd")
		(comment 1 "Open CloudServer (Microsoft) / footprints 1-8 of 2512")
	)
	(layers
		(0 "F.Cu" signal "TOP")
		(4 "In1.Cu" signal "GND1")
		(6 "In2.Cu" signal "IN1")
		(8 "In3.Cu" signal "VCC1")
		(10 "In4.Cu" signal "VCC2")
		(12 "In5.Cu" signal "GND2")
		(14 "In6.Cu" signal "IN2")
		(16 "In7.Cu" signal "IN3")
		(18 "In8.Cu" signal "GND3")
		(2 "B.Cu" signal "BOTTOM")
		(9 "F.Adhes" user "F.Adhesive")
		(11 "B.Adhes" user "B.Adhesive")
		(13 "F.Paste" user "Package Geometry/Pastemask Top")
		(15 "B.Paste" user "Package Geometry/Pastemask Bottom")
		(5 "F.SilkS" user "Ref Des/Silkscreen Top")
		(7 "B.SilkS" user "Ref Des/Silkscreen Bottom")
		(1 "F.Mask" user "Board Geometry/Soldermask Top")
		(3 "B.Mask" user "Board Geometry/Soldermask Bottom")
		(17 "Dwgs.User" user "User.Drawings")
		(19 "Cmts.User" user "User.Comments")
		(21 "Eco1.User" user "User.Eco1")
		(23 "Eco2.User" user "User.Eco2")
		(25 "Edge.Cuts" user "Board Geometry/Outline")
		(27 "Margin" user)
		(31 "F.CrtYd" user "Package Geometry/Place Bound Top")
		(29 "B.CrtYd" user "Package Geometry/Place Bound Bottom")
		(35 "F.Fab" user "Ref Des/Assembly Top")
		(33 "B.Fab" user "Ref Des/Assembly Bottom")
	)
	(footprint ""
		(layer "F.Cu")
		(at 35.669728 -78.877922)
		(property "Reference" "R43"
			(at -4.58851 -0.106934 0)
			(unlocked yes)
			(layer "F.SilkS")
			(effects
				(font
					(size 0.7874 0.5842)
					(thickness 0.1524)
				)
				(justify left)
			)
		)
		(property "Value" ""
			(at 0 0 0)
			(layer "F.Fab")
			(effects
				(font
					(size 1.27 1.27)
				)
			)
		)
		(duplicate_pad_numbers_are_jumpers no)
		(fp_line
			(start -0.7874 -0.4064)
			(end 0.7874 -0.4064)
			(stroke
				(width 0.1524)
				(type default)
			)
			(layer "F.SilkS")
		)
		(fp_line
			(start -0.7874 0.4064)
			(end -0.7874 -0.4064)
			(stroke
				(width 0.1524)
				(type default)
			)
			(layer "F.SilkS")
		)
		(fp_line
			(start 0.7874 -0.4064)
			(end 0.7874 0.4064)
			(stroke
				(width 0.1524)
				(type default)
			)
			(layer "F.SilkS")
		)
		(fp_line
			(start 0.7874 0.4064)
			(end -0.7874 0.4064)
			(stroke
				(width 0.1524)
				(type default)
			)
			(layer "F.SilkS")
		)
		(fp_poly
			(pts
				(xy -0.508 0.2794) (xy -0.508 0.2286) (xy -0.635 0.2286) (xy -0.635 -0.254) (xy -0.5334 -0.254)
				(xy -0.5334 -0.2794) (xy 0.5334 -0.2794) (xy 0.5334 -0.254) (xy 0.635 -0.254) (xy 0.635 0.254) (xy 0.5334 0.254)
				(xy 0.5334 0.2794)
			)
			(stroke
				(width 0)
				(type default)
			)
			(fill no)
			(layer "F.CrtYd")
		)
		(pad "1" smd rect
			(at 0.40005 0)
			(size 0.4572 0.508)
			(layers "F.Cu" "F.Mask" "F.Paste")
			(net "PD_CPU_NODE1_RP2_PERP")
		)
		(pad "2" smd rect
			(at -0.40005 0)
			(size 0.4572 0.508)
			(layers "F.Cu" "F.Mask" "F.Paste")
			(net "GND")
		)
	)
	(footprint ""
		(layer "F.Cu")
		(at 149.411944 -44.680124)
		(property "Reference" "R1010"
			(at -2.3368 -2.962148 0)
			(unlocked yes)
			(layer "F.SilkS")
			(effects
				(font
					(size 0.7874 0.5842)
					(thickness 0.1524)
				)
				(justify left)
			)
		)
		(property "Value" ""
			(at 0 0 0)
			(layer "F.Fab")
			(effects
				(font
					(size 1.27 1.27)
				)
			)
		)
		(duplicate_pad_numbers_are_jumpers no)
		(fp_line
			(start -0.7874 -0.4064)
			(end 0.7874 -0.4064)
			(stroke
				(width 0.1524)
				(type default)
			)
			(layer "F.SilkS")
		)
		(fp_line
			(start -0.7874 0.4064)
			(end -0.7874 -0.4064)
			(stroke
				(width 0.1524)
				(type default)
			)
			(layer "F.SilkS")
		)
		(fp_line
			(start 0.7874 -0.4064)
			(end 0.7874 0.4064)
			(stroke
				(width 0.1524)
				(type default)
			)
			(layer "F.SilkS")
		)
		(fp_line
			(start 0.7874 0.4064)
			(end -0.7874 0.4064)
			(stroke
				(width 0.1524)
				(type default)
			)
			(layer "F.SilkS")
		)
		(fp_poly
			(pts
				(xy -0.508 0.2794) (xy -0.508 0.2286) (xy -0.635 0.2286) (xy -0.635 -0.254) (xy -0.5334 -0.254)
				(xy -0.5334 -0.2794) (xy 0.5334 -0.2794) (xy 0.5334 -0.254) (xy 0.635 -0.254) (xy 0.635 0.254) (xy 0.5334 0.254)
				(xy 0.5334 0.2794)
			)
			(stroke
				(width 0)
				(type default)
			)
			(fill no)
			(layer "F.CrtYd")
		)
		(pad "1" smd rect
			(at 0.40005 0)
			(size 0.4572 0.508)
			(layers "F.Cu" "F.Mask" "F.Paste")
			(net "GND")
		)
		(pad "2" smd rect
			(at -0.40005 0)
			(size 0.4572 0.508)
			(layers "F.Cu" "F.Mask" "F.Paste")
			(net "UART_TX_P1")
		)
	)
	(footprint ""
		(layer "F.Cu")
		(at 54.344062 -151.627078)
		(property "Reference" "C392"
			(at -2.298192 -2.007362 0)
			(unlocked yes)
			(layer "F.SilkS")
			(effects
				(font
					(size 0.7874 0.5842)
					(thickness 0.1524)
				)
				(justify left)
			)
		)
		(property "Value" ""
			(at 0 0 0)
			(layer "F.Fab")
			(effects
				(font
					(size 1.27 1.27)
				)
			)
		)
		(duplicate_pad_numbers_are_jumpers no)
		(fp_line
			(start -0.7874 -0.4064)
			(end 0.7874 -0.4064)
			(stroke
				(width 0.1524)
				(type default)
			)
			(layer "F.SilkS")
		)
		(fp_line
			(start -0.7874 0.4064)
			(end -0.7874 -0.4064)
			(stroke
				(width 0.1524)
				(type default)
			)
			(layer "F.SilkS")
		)
		(fp_line
			(start 0 0.381)
			(end 0 -0.381)
			(stroke
				(width 0.1524)
				(type default)
			)
			(layer "F.SilkS")
		)
		(fp_line
			(start 0.7874 -0.4064)
			(end 0.7874 0.4064)
			(stroke
				(width 0.1524)
				(type default)
			)
			(layer "F.SilkS")
		)
		(fp_line
			(start 0.7874 0.4064)
			(end -0.7874 0.4064)
			(stroke
				(width 0.1524)
				(type default)
			)
			(layer "F.SilkS")
		)
		(fp_poly
			(pts
				(xy -0.5334 0.254) (xy -0.635 0.254) (xy -0.635 0.2286) (xy -0.635 -0.254) (xy -0.5334 -0.254) (xy -0.5334 -0.2794)
				(xy 0.5334 -0.2794) (xy 0.5334 -0.254) (xy 0.635 -0.254) (xy 0.635 0.254) (xy 0.5334 0.254) (xy 0.5334 0.2794)
				(xy -0.508 0.2794) (xy -0.5334 0.2794)
			)
			(stroke
				(width 0)
				(type default)
			)
			(fill no)
			(layer "F.CrtYd")
		)
		(pad "1" smd rect
			(at 0.40005 0)
			(size 0.4572 0.508)
			(layers "F.Cu" "F.Mask" "F.Paste")
			(net "P2E_CPU_NIC1_NODE1_RX_DN")
		)
		(pad "2" smd rect
			(at -0.40005 0)
			(size 0.4572 0.508)
			(layers "F.Cu" "F.Mask" "F.Paste")
			(net "PCIE_LAN1_RX_C_DN")
		)
	)
	(footprint ""
		(layer "F.Cu")
		(at 69.084698 -17.679416 90)
		(property "Reference" "C161"
			(at -2.143252 -2.04597 90)
			(unlocked yes)
			(layer "F.SilkS")
			(effects
				(font
					(size 0.7874 0.5842)
					(thickness 0.1524)
				)
				(justify left)
			)
		)
		(property "Value" ""
			(at 0 0 90)
			(layer "F.Fab")
			(effects
				(font
					(size 1.27 1.27)
				)
			)
		)
		(duplicate_pad_numbers_are_jumpers no)
		(fp_line
			(start 0.7874 -0.4064)
			(end 0.7874 0.4064)
			(stroke
				(width 0.1524)
				(type default)
			)
			(layer "F.SilkS")
		)
		(fp_line
			(start -0.7874 -0.4064)
			(end 0.7874 -0.4064)
			(stroke
				(width 0.1524)
				(type default)
			)
			(layer "F.SilkS")
		)
		(fp_line
			(start 0 0.381)
			(end 0 -0.381)
			(stroke
				(width 0.1524)
				(type default)
			)
			(layer "F.SilkS")
		)
		(fp_line
			(start 0.7874 0.4064)
			(end -0.7874 0.4064)
			(stroke
				(width 0.1524)
				(type default)
			)
			(layer "F.SilkS")
		)
		(fp_line
			(start -0.7874 0.4064)
			(end -0.7874 -0.4064)
			(stroke
				(width 0.1524)
				(type default)
			)
			(layer "F.SilkS")
		)
		(fp_poly
			(pts
				(xy -0.5334 0.254) (xy -0.635 0.254) (xy -0.635 0.2286) (xy -0.635 -0.254) (xy -0.5334 -0.254) (xy -0.5334 -0.2794)
				(xy 0.5334 -0.2794) (xy 0.5334 -0.254) (xy 0.635 -0.254) (xy 0.635 0.254) (xy 0.5334 0.254) (xy 0.5334 0.2794)
				(xy -0.508 0.2794) (xy -0.5334 0.2794)
			)
			(stroke
				(width 0)
				(type default)
			)
			(fill no)
			(layer "F.CrtYd")
		)
		(pad "1" smd rect
			(at 0.40005 0 90)
			(size 0.4572 0.508)
			(layers "F.Cu" "F.Mask" "F.Paste")
			(net "PV_VDDR_NODE1")
		)
		(pad "2" smd rect
			(at -0.40005 0 90)
			(size 0.4572 0.508)
			(layers "F.Cu" "F.Mask" "F.Paste")
			(net "GND")
		)
	)
	(footprint ""
		(layer "F.Cu")
		(at 89.39276 -185.205624 90)
		(property "Reference" "C708"
			(at 4.198112 -2.154682 90)
			(unlocked yes)
			(layer "F.SilkS")
			(effects
				(font
					(size 0.7874 0.5842)
					(thickness 0.1524)
				)
				(justify left)
			)
		)
		(property "Value" ""
			(at 0 0 90)
			(layer "F.Fab")
			(effects
				(font
					(size 1.27 1.27)
				)
			)
		)
		(duplicate_pad_numbers_are_jumpers no)
		(fp_line
			(start 0.7874 -0.4064)
			(end 0.7874 0.4064)
			(stroke
				(width 0.1524)
				(type default)
			)
			(layer "F.SilkS")
		)
		(fp_line
			(start -0.7874 -0.4064)
			(end 0.7874 -0.4064)
			(stroke
				(width 0.1524)
				(type default)
			)
			(layer "F.SilkS")
		)
		(fp_line
			(start 0 0.381)
			(end 0 -0.381)
			(stroke
				(width 0.1524)
				(type default)
			)
			(layer "F.SilkS")
		)
		(fp_line
			(start 0.7874 0.4064)
			(end -0.7874 0.4064)
			(stroke
				(width 0.1524)
				(type default)
			)
			(layer "F.SilkS")
		)
		(fp_line
			(start -0.7874 0.4064)
			(end -0.7874 -0.4064)
			(stroke
				(width 0.1524)
				(type default)
			)
			(layer "F.SilkS")
		)
		(fp_poly
			(pts
				(xy -0.5334 0.254) (xy -0.635 0.254) (xy -0.635 0.2286) (xy -0.635 -0.254) (xy -0.5334 -0.254) (xy -0.5334 -0.2794)
				(xy 0.5334 -0.2794) (xy 0.5334 -0.254) (xy 0.635 -0.254) (xy 0.635 0.254) (xy 0.5334 0.254) (xy 0.5334 0.2794)
				(xy -0.508 0.2794) (xy -0.5334 0.2794)
			)
			(stroke
				(width 0)
				(type default)
			)
			(fill no)
			(layer "F.CrtYd")
		)
		(pad "1" smd rect
			(at 0.40005 0 90)
			(size 0.4572 0.508)
			(layers "F.Cu" "F.Mask" "F.Paste")
			(net "UART_T6_NODE3_RXD")
		)
		(pad "2" smd rect
			(at -0.40005 0 90)
			(size 0.4572 0.508)
			(layers "F.Cu" "F.Mask" "F.Paste")
			(net "GND")
		)
	)
	(footprint ""
		(layer "F.Cu")
		(at 73.442068 -94.131892 -90)
		(property "Reference" "R151"
			(at 55.53329 -24.083264 90)
			(unlocked yes)
			(layer "F.SilkS")
			(effects
				(font
					(size 0.7874 0.5842)
					(thickness 0.1524)
				)
				(justify left)
			)
		)
		(property "Value" ""
			(at 0 0 270)
			(layer "F.Fab")
			(effects
				(font
					(size 1.27 1.27)
				)
			)
		)
		(duplicate_pad_numbers_are_jumpers no)
		(fp_line
			(start -0.7874 0.4064)
			(end -0.7874 -0.4064)
			(stroke
				(width 0.1524)
				(type default)
			)
			(layer "F.SilkS")
		)
		(fp_line
			(start 0.7874 0.4064)
			(end -0.7874 0.4064)
			(stroke
				(width 0.1524)
				(type default)
			)
			(layer "F.SilkS")
		)
		(fp_line
			(start -0.7874 -0.4064)
			(end 0.7874 -0.4064)
			(stroke
				(width 0.1524)
				(type default)
			)
			(layer "F.SilkS")
		)
		(fp_line
			(start 0.7874 -0.4064)
			(end 0.7874 0.4064)
			(stroke
				(width 0.1524)
				(type default)
			)
			(layer "F.SilkS")
		)
		(fp_poly
			(pts
				(xy -0.508 0.2794) (xy -0.508 0.2286) (xy -0.635 0.2286) (xy -0.635 -0.254) (xy -0.5334 -0.254)
				(xy -0.5334 -0.2794) (xy 0.5334 -0.2794) (xy 0.5334 -0.254) (xy 0.635 -0.254) (xy 0.635 0.254) (xy 0.5334 0.254)
				(xy 0.5334 0.2794)
			)
			(stroke
				(width 0)
				(type default)
			)
			(fill no)
			(layer "F.CrtYd")
		)
		(pad "1" smd rect
			(at 0.40005 0 270)
			(size 0.4572 0.508)
			(layers "F.Cu" "F.Mask" "F.Paste")
			(net "PD_CPU_NODE1_BOOTDEVSEL")
		)
		(pad "2" smd rect
			(at -0.40005 0 270)
			(size 0.4572 0.508)
			(layers "F.Cu" "F.Mask" "F.Paste")
			(net "P3V3_NODE1")
		)
	)
	(footprint ""
		(layer "F.Cu")
		(at 135.109966 -55.324502 90)
		(property "Reference" "R1134"
			(at 0.936498 -0.285496 90)
			(unlocked yes)
			(layer "F.SilkS")
			(effects
				(font
					(size 0.7874 0.5842)
					(thickness 0.1524)
				)
				(justify left)
			)
		)
		(property "Value" ""
			(at 0 0 90)
			(layer "F.Fab")
			(effects
				(font
					(size 1.27 1.27)
				)
			)
		)
		(duplicate_pad_numbers_are_jumpers no)
		(fp_line
			(start 0.7874 -0.4064)
			(end 0.7874 0.4064)
			(stroke
				(width 0.1524)
				(type default)
			)
			(layer "F.SilkS")
		)
		(fp_line
			(start -0.7874 -0.4064)
			(end 0.7874 -0.4064)
			(stroke
				(width 0.1524)
				(type default)
			)
			(layer "F.SilkS")
		)
		(fp_line
			(start 0.7874 0.4064)
			(end -0.7874 0.4064)
			(stroke
				(width 0.1524)
				(type default)
			)
			(layer "F.SilkS")
		)
		(fp_line
			(start -0.7874 0.4064)
			(end -0.7874 -0.4064)
			(stroke
				(width 0.1524)
				(type default)
			)
			(layer "F.SilkS")
		)
		(fp_poly
			(pts
				(xy -0.508 0.2794) (xy -0.508 0.2286) (xy -0.635 0.2286) (xy -0.635 -0.254) (xy -0.5334 -0.254)
				(xy -0.5334 -0.2794) (xy 0.5334 -0.2794) (xy 0.5334 -0.254) (xy 0.635 -0.254) (xy 0.635 0.254) (xy 0.5334 0.254)
				(xy 0.5334 0.2794)
			)
			(stroke
				(width 0)
				(type default)
			)
			(fill no)
			(layer "F.CrtYd")
		)
		(pad "1" smd rect
			(at 0.40005 0 90)
			(size 0.4572 0.508)
			(layers "F.Cu" "F.Mask" "F.Paste")
			(net "P5V_NODE1")
		)
		(pad "2" smd rect
			(at -0.40005 0 90)
			(size 0.4572 0.508)
			(layers "F.Cu" "F.Mask" "F.Paste")
			(net "UART_TX_P3_R")
		)
	)
	(footprint ""
		(layer "F.Cu")
		(at 88.77046 -15.804388 90)
		(property "Reference" "R194"
			(at -1.882394 1.419606 90)
			(unlocked yes)
			(layer "F.SilkS")
			(effects
				(font
					(size 0.7874 0.5842)
					(thickness 0.1524)
				)
				(justify left)
			)
		)
		(property "Value" ""
			(at 0 0 90)
			(layer "F.Fab")
			(effects
				(font
					(size 1.27 1.27)
				)
			)
		)
		(duplicate_pad_numbers_are_jumpers no)
		(fp_line
			(start 0.7874 -0.406146)
			(end 0.7874 0.406146)
			(stroke
				(width 0.1524)
				(type default)
			)
			(layer "F.SilkS")
		)
		(fp_line
			(start -0.7874 -0.406146)
			(end 0.7874 -0.406146)
			(stroke
				(width 0.1524)
				(type default)
			)
			(layer "F.SilkS")
		)
		(fp_line
			(start 0.7874 0.406146)
			(end -0.7874 0.406146)
			(stroke
				(width 0.1524)
				(type default)
			)
			(layer "F.SilkS")
		)
		(fp_line
			(start -0.7874 0.406146)
			(end -0.7874 -0.406146)
			(stroke
				(width 0.1524)
				(type default)
			)
			(layer "F.SilkS")
		)
		(fp_poly
			(pts
				(xy -0.508 0.2794) (xy -0.508 0.2286) (xy -0.635 0.2286) (xy -0.635 -0.254) (xy -0.5334 -0.254)
				(xy -0.5334 -0.2794) (xy 0.5334 -0.2794) (xy 0.5334 -0.254) (xy 0.635 -0.254) (xy 0.635 0.254) (xy 0.5334 0.254)
				(xy 0.5334 0.2794)
			)
			(stroke
				(width 0)
				(type default)
			)
			(fill no)
			(layer "F.CrtYd")
		)
		(pad "1" smd rect
			(at 0.40005 0 90)
			(size 0.4572 0.508)
			(layers "F.Cu" "F.Mask" "F.Paste")
			(net "LPC_CPU_NODE1_FRAME_L")
		)
		(pad "2" smd rect
			(at -0.40005 0 90)
			(size 0.4572 0.508)
			(layers "F.Cu" "F.Mask" "F.Paste")
			(net "N20512383")
		)
	)
)
